G04 ================== begin FILE IDENTIFICATION RECORD ==================*
G04 Layout Name:  DA0T6MTH8C0_t6m_tray_bp_c_brd_103112_274.brd*
G04 Film Name:    outline*
G04 File Format:  Gerber RS274X*
G04 File Origin:  Cadence Allegro 16.3-S048*
G04 Origin Date:  Tue Nov 26 11:26:41 2013*
G04 *
G04 Layer:  BOARD GEOMETRY/OUTLINE*
G04 *
G04 Offset:    (0.00 0.00)*
G04 Mirror:    No*
G04 Mode:      Positive*
G04 Rotation:  0*
G04 FullContactRelief:  No*
G04 UndefLineWidth:     6.00*
G04 ================== end FILE IDENTIFICATION RECORD ====================*
%FSLAX25Y25*MOIN*%
%IR0*IPPOS*OFA0.00000B0.00000*MIA0B0*SFA1.00000B1.00000*%
%ADD10C,.006*%
G75*
%LPD*%
G75*
G54D10*
G01X1683504Y165354D02*
Y190512D01*
G03X1675630Y198386I-7874J0D01*
G01X1503898D01*
X1502406Y198679D01*
X1501137Y199516D01*
X1500279Y200772D01*
X1499930Y202268D01*
X1499661Y203554D01*
X1498808Y204831D01*
X1497530Y205685D01*
X1496024Y205984D01*
X1468465D01*
G03X1464528Y202047I0J-3937D01*
G01Y200000D01*
G02X1460591Y196063I-3937J0D01*
G01X1401535D01*
G02X1397598Y200000I0J3937D01*
G01Y202047D01*
G03X1393661Y205984I-3937J0D01*
G01X1319173D01*
G03X1315236Y202047I0J-3937D01*
G01Y200000D01*
G02X1311299Y196063I-3937J0D01*
G01X1252244D01*
G02X1248307Y200000I0J3937D01*
G01Y202047D01*
G03X1244370Y205984I-3937J0D01*
G01X807047D01*
X805541Y205685D01*
X804263Y204831D01*
X803410Y203554D01*
X803141Y202268D01*
X802792Y200772D01*
X801934Y199516D01*
X800665Y198679D01*
X799173Y198386D01*
X633819D01*
X632327Y198679D01*
X631058Y199516D01*
X630200Y200772D01*
X629851Y202268D01*
X629582Y203554D01*
X628729Y204831D01*
X627451Y205685D01*
X625945Y205984D01*
X598386D01*
G03X594449Y202047I0J-3937D01*
G01Y200000D01*
G02X590512Y196063I-3937J0D01*
G01X531457D01*
G02X527520Y200000I0J3937D01*
G01Y202047D01*
G03X523583Y205984I-3937J0D01*
G01X449094D01*
G03X445157Y202047I0J-3937D01*
G01Y200000D01*
G02X441220Y196063I-3937J0D01*
G01X382165D01*
G02X378228Y200000I0J3937D01*
G01Y202047D01*
G03X374291Y205984I-3937J0D01*
G01X228661D01*
G03X220787Y198110I0J-7874D01*
G01Y170551D01*
G02X216850Y166614I-3937J0D01*
G01X208976D01*
G02X205039Y170551I0J3937D01*
G01Y203937D01*
X199134Y209842D01*
X49803D01*
X43898Y203937D01*
Y167913D01*
G02X41142I-1378J0D01*
G01Y203937D01*
X37205Y207874D01*
X35236Y209842D01*
X5906D01*
X3937Y207874D01*
X0Y203937D01*
Y7874D01*
G03X7874Y0I7874J0D01*
G01X1680354D01*
G03X1688228Y7874I0J7874D01*
G01Y39370D01*
G03X1686260Y41339I-1969J0D01*
G01X1685472D01*
G02X1683504Y43307I0J1968D01*
G01Y122047D01*
G03X1681535Y124016I-1969J0D01*
G01X1675236D01*
G02X1673268Y125984I0J1968D01*
G01Y161417D01*
G02X1675236Y163386I1968J1D01*
G01X1681535D01*
G03X1683504Y165354I1J1968D01*
G01X10433Y114173D02*
Y128497D01*
G02X25000I7283J9298D01*
G01Y114173D01*
G02X10433I-7284J0D01*
G01X306929Y163386D02*
Y177710D01*
G02X321496I7283J9298D01*
G01Y163386D01*
G02X306929I-7283J0D01*
G01X776772Y18504D02*
Y32533D01*
G02X790551I6889J9593D01*
G01Y18504D01*
G02X776772I-6890J0D01*
G01X819134Y163386D02*
Y177415D01*
G02X832913I6890J9593D01*
G01Y163386D01*
G02X819134I-6889J0D01*
G01X1094331Y18504D02*
Y32828D01*
G02X1108898I7283J9298D01*
G01Y18504D01*
G02X1094331I-7283J0D01*
G01X1177008Y163386D02*
Y177710D01*
G02X1191575I7284J9298D01*
G01Y163386D01*
G02X1177008I-7283J0D01*
M02*
